(kicad_pcb
	(version 20260206)
	(generator "pcbnew")
	(generator_version "10.0")
	(general
		(thickness 1.21888)
		(legacy_teardrops no)
	)
	(paper "A4")
	(title_block
		(title "timecard-v7 — TimeCard-DC-V7_EXP.PcbDoc")
		(comment 1 "Time Appliance Project (Time Card) / footprints 133-136 of 160")
	)
	(layers
		(0 "F.Cu" signal "TOP")
		(4 "In1.Cu" signal "SGND")
		(6 "In2.Cu" signal "IN1")
		(8 "In3.Cu" signal "IN2")
		(10 "In4.Cu" signal "SGND1")
		(2 "B.Cu" signal "BOTTOM")
		(9 "F.Adhes" user "F.Adhesive")
		(11 "B.Adhes" user "B.Adhesive")
		(13 "F.Paste" user "Top Paste")
		(15 "B.Paste" user "Bottom Paste")
		(5 "F.SilkS" user "Top Overlay")
		(7 "B.SilkS" user "Bottom Overlay")
		(1 "F.Mask" user "Top Solder")
		(3 "B.Mask" user "Bottom Solder")
		(17 "Dwgs.User" user "User.Drawings")
		(19 "Cmts.User" user "User.Comments")
		(21 "Eco1.User" user "User.Eco1")
		(23 "Eco2.User" user "User.Eco2")
		(25 "Edge.Cuts" user)
		(27 "Margin" user)
		(31 "F.CrtYd" user "Top Courtyard")
		(29 "B.CrtYd" user "Bottom Courtyard")
		(35 "F.Fab" user "Top Component Center")
		(33 "B.Fab" user "Bottom Component Center")
	)
	(footprint "Vault:SOT143-4L"
		(layer "F.Cu")
		(at 71.8761 100.7662 90)
		(property "Reference" "D1"
			(at -2.776921 1.478595 0)
			(unlocked yes)
			(layer "F.SilkS")
			(effects
				(font
					(size 0.762 0.762)
					(thickness 0.2286)
				)
			)
		)
		(property "Value" "8240136"
			(at 2.7035 3.368802 90)
			(unlocked yes)
			(layer "F.SilkS")
			(hide yes)
			(effects
				(font
					(size 1.524 1.524)
					(thickness 0.254)
				)
			)
		)
		(sheetname "USER_IO")
		(sheetfile "USER_IO.kicad_sch")
		(duplicate_pad_numbers_are_jumpers no)
		(fp_line
			(start 2.05 -1.7)
			(end 2.05 1.7)
			(stroke
				(width 0.2)
				(type solid)
			)
			(layer "F.SilkS")
		)
		(fp_line
			(start -2.05 -1.7)
			(end 2.05 -1.7)
			(stroke
				(width 0.2)
				(type solid)
			)
			(layer "F.SilkS")
		)
		(fp_line
			(start -2.05 -1.7)
			(end -2.05 1.675)
			(stroke
				(width 0.2)
				(type solid)
			)
			(layer "F.SilkS")
		)
		(fp_line
			(start -2.05 1.7)
			(end 2.05 1.7)
			(stroke
				(width 0.2)
				(type solid)
			)
			(layer "F.SilkS")
		)
		(fp_circle
			(center -2.404 -1.075)
			(end -2.15 -1.075)
			(stroke
				(width 0.2)
				(type solid)
			)
			(fill no)
			(layer "F.SilkS")
		)
		(pad "1" smd rect
			(at -1.1 -0.75 180)
			(size 1.4 1.4)
			(layers "F.Cu" "F.Mask" "F.Paste")
			(net "GND")
		)
		(pad "2" smd rect
			(at -1.1 0.95 180)
			(size 1 1.4)
			(layers "F.Cu" "F.Mask" "F.Paste")
			(net "NetAN2_1")
		)
		(pad "3" smd rect
			(at 1.1 0.95 180)
			(size 1 1.4)
			(layers "F.Cu" "F.Mask" "F.Paste")
			(net "NetAN1_1")
		)
		(pad "4" smd rect
			(at 1.1 -0.95 180)
			(size 1 1.4)
			(layers "F.Cu" "F.Mask" "F.Paste")
			(net "+3.3V")
		)
	)
	(footprint "Vault:CAPC1608X87X45ML20T05"
		(layer "F.Cu")
		(at 176.8761 87.0786 -90)
		(property "Reference" "C25"
			(at -2.723069 -0.2286 0)
			(unlocked yes)
			(layer "F.SilkS")
			(effects
				(font
					(size 0.762 0.762)
					(thickness 0.2286)
				)
			)
		)
		(property "Value" "0.1uF"
			(at 2.09443 2.657602 270)
			(unlocked yes)
			(layer "F.SilkS")
			(hide yes)
			(effects
				(font
					(size 1.524 1.524)
					(thickness 0.254)
				)
			)
		)
		(sheetname "GPS_IMU_SENSORS")
		(sheetfile "GPS_IMU_SENSORS.kicad_sch")
		(duplicate_pad_numbers_are_jumpers no)
		(pad "1" smd rect
			(at -0.7 0)
			(size 1.1 1.05)
			(layers "F.Cu" "F.Mask" "F.Paste")
			(net "GND")
		)
		(pad "2" smd rect
			(at 0.7 0)
			(size 1.1 1.05)
			(layers "F.Cu" "F.Mask" "F.Paste")
			(net "+3.3V")
		)
	)
	(footprint "Vault:CAPC1608X87X45ML20T05"
		(layer "F.Cu")
		(at 214.2637 90.4662 90)
		(property "Reference" "C12"
			(at 4.2 0.106655 270)
			(unlocked yes)
			(layer "F.SilkS")
			(effects
				(font
					(size 0.762 0.762)
					(thickness 0.2286)
				)
				(justify left bottom)
			)
		)
		(property "Value" "0.1uF"
			(at -10.00739 4.2013 0)
			(unlocked yes)
			(layer "F.SilkS")
			(hide yes)
			(effects
				(font
					(size 1.524 1.524)
					(thickness 0.254)
				)
				(justify left bottom)
			)
		)
		(sheetname "POWER")
		(sheetfile "POWER.kicad_sch")
		(duplicate_pad_numbers_are_jumpers no)
		(pad "1" smd rect
			(at -0.7 0 180)
			(size 1.1 1.05)
			(layers "F.Cu" "F.Mask" "F.Paste")
			(net "GND")
		)
		(pad "2" smd rect
			(at 0.7 0 180)
			(size 1.1 1.05)
			(layers "F.Cu" "F.Mask" "F.Paste")
			(net "+3.3V")
		)
	)
	(footprint "FPGA_CONN:SingleFPGAConn"
		(layer "F.Cu")
		(at 197.33851 104.56486 180)
		(property "Reference" "J34"
			(at -0.368955 -23.428198 180)
			(unlocked yes)
			(layer "F.SilkS")
			(effects
				(font
					(size 1.524 1.524)
					(thickness 0.254)
				)
			)
		)
		(property "Value" "Single FPGA Conn"
			(at 9.27992 3.521202 180)
			(unlocked yes)
			(layer "F.SilkS")
			(hide yes)
			(effects
				(font
					(size 1.524 1.524)
					(thickness 0.254)
				)
			)
		)
		(sheetname "FPGA")
		(sheetfile "FPGA.kicad_sch")
		(duplicate_pad_numbers_are_jumpers no)
		(fp_line
			(start 2 0.70003)
			(end 1.40005 0.70003)
			(stroke
				(width 0.15011)
				(type solid)
			)
			(layer "F.SilkS")
		)
		(fp_line
			(start 2 0.03302)
			(end 2 0.70003)
			(stroke
				(width 0.15011)
				(type solid)
			)
			(layer "F.SilkS")
		)
		(fp_line
			(start 2 -20.69998)
			(end 2 -20.03298)
			(stroke
				(width 0.15011)
				(type solid)
			)
			(layer "F.SilkS")
		)
		(fp_line
			(start 2 -20.69998)
			(end 1.40005 -20.69998)
			(stroke
				(width 0.15011)
				(type solid)
			)
			(layer "F.SilkS")
		)
		(fp_line
			(start 1.40005 1.24994)
			(end -1.40005 1.24994)
			(stroke
				(width 0.15011)
				(type solid)
			)
			(layer "F.SilkS")
		)
		(fp_line
			(start 1.40005 0.70003)
			(end 1.40005 1.24994)
			(stroke
				(width 0.15011)
				(type solid)
			)
			(layer "F.SilkS")
		)
		(fp_line
			(start 1.40005 -21.24989)
			(end 1.40005 -20.69998)
			(stroke
				(width 0.15011)
				(type solid)
			)
			(layer "F.SilkS")
		)
		(fp_line
			(start 1.40005 -21.24989)
			(end -1.40005 -21.24989)
			(stroke
				(width 0.15011)
				(type solid)
			)
			(layer "F.SilkS")
		)
		(fp_line
			(start -1.40005 0.70003)
			(end -1.40005 1.24994)
			(stroke
				(width 0.15011)
				(type solid)
			)
			(layer "F.SilkS")
		)
		(fp_line
			(start -1.40005 0.70003)
			(end -2 0.70003)
			(stroke
				(width 0.15011)
				(type solid)
			)
			(layer "F.SilkS")
		)
		(fp_line
			(start -1.40005 -20.69998)
			(end -2 -20.69998)
			(stroke
				(width 0.15011)
				(type solid)
			)
			(layer "F.SilkS")
		)
		(fp_line
			(start -1.40005 -21.24989)
			(end -1.40005 -20.69998)
			(stroke
				(width 0.15011)
				(type solid)
			)
			(layer "F.SilkS")
		)
		(fp_line
			(start -2 0.03302)
			(end -2 0.70003)
			(stroke
				(width 0.15011)
				(type solid)
			)
			(layer "F.SilkS")
		)
		(fp_line
			(start -2 -20.69998)
			(end -2 -20.03298)
			(stroke
				(width 0.15011)
				(type solid)
			)
			(layer "F.SilkS")
		)
		(fp_circle
			(center 3.5052 -0.22453)
			(end 3.5052 -0.02438)
			(stroke
				(width 0.40005)
				(type solid)
			)
			(fill no)
			(layer "F.SilkS")
		)
		(pad "1" smd rect
			(at 2.02489 -0.24993 180)
			(size 1.54991 0.24994)
			(layers "F.Cu" "F.Mask" "F.Paste")
			(net "+5.0V")
		)
		(pad "2" smd rect
			(at -2.02489 -0.24993 180)
			(size 1.54991 0.24994)
			(layers "F.Cu" "F.Mask" "F.Paste")
			(net "+5.0V")
		)
		(pad "3" smd rect
			(at 2.02489 -0.75006 180)
			(size 1.54991 0.24994)
			(layers "F.Cu" "F.Mask" "F.Paste")
			(net "+5.0V")
		)
		(pad "4" smd rect
			(at -2.02489 -0.75006 180)
			(size 1.54991 0.24994)
			(layers "F.Cu" "F.Mask" "F.Paste")
			(net "+5.0V")
		)
		(pad "5" smd rect
			(at 2.02489 -1.24993 180)
			(size 1.54991 0.24994)
			(layers "F.Cu" "F.Mask" "F.Paste")
			(net "+5.0V")
		)
		(pad "6" smd rect
			(at -2.02489 -1.24993 180)
			(size 1.54991 0.24994)
			(layers "F.Cu" "F.Mask" "F.Paste")
			(net "+5.0V")
		)
		(pad "7" smd rect
			(at 2.02489 -1.75006 180)
			(size 1.54991 0.24994)
			(layers "F.Cu" "F.Mask" "F.Paste")
			(net "+5.0V")
		)
		(pad "8" smd rect
			(at -2.02489 -1.75006 180)
			(size 1.54991 0.24994)
			(layers "F.Cu" "F.Mask" "F.Paste")
			(net "+5.0V")
		)
		(pad "9" smd rect
			(at 2.02489 -2.24993 180)
			(size 1.54991 0.24994)
			(layers "F.Cu" "F.Mask" "F.Paste")
			(net "GND")
		)
		(pad "10" smd rect
			(at -2.02489 -2.24993 180)
			(size 1.54991 0.24994)
			(layers "F.Cu" "F.Mask" "F.Paste")
			(net "GND")
		)
		(pad "11" smd rect
			(at 2.02489 -2.75006 180)
			(size 1.54991 0.24994)
			(layers "F.Cu" "F.Mask" "F.Paste")
		)
		(pad "12" smd rect
			(at -2.02489 -2.75006 180)
			(size 1.54991 0.24994)
			(layers "F.Cu" "F.Mask" "F.Paste")
		)
		(pad "13" smd rect
			(at 2.02489 -3.24993 180)
			(size 1.54991 0.24994)
			(layers "F.Cu" "F.Mask" "F.Paste")
		)
		(pad "14" smd rect
			(at -2.02489 -3.24993 180)
			(size 1.54991 0.24994)
			(layers "F.Cu" "F.Mask" "F.Paste")
		)
		(pad "15" smd rect
			(at 2.02489 -3.75005 180)
			(size 1.54991 0.24994)
			(layers "F.Cu" "F.Mask" "F.Paste")
		)
		(pad "16" smd rect
			(at -2.02489 -3.75005 180)
			(size 1.54991 0.24994)
			(layers "F.Cu" "F.Mask" "F.Paste")
		)
		(pad "17" smd rect
			(at 2.02489 -4.24993 180)
			(size 1.54991 0.24994)
			(layers "F.Cu" "F.Mask" "F.Paste")
		)
		(pad "18" smd rect
			(at -2.02489 -4.24993 180)
			(size 1.54991 0.24994)
			(layers "F.Cu" "F.Mask" "F.Paste")
		)
		(pad "19" smd rect
			(at 2.02489 -4.75005 180)
			(size 1.54991 0.24994)
			(layers "F.Cu" "F.Mask" "F.Paste")
			(net "GND")
		)
		(pad "20" smd rect
			(at -2.02489 -4.75005 180)
			(size 1.54991 0.24994)
			(layers "F.Cu" "F.Mask" "F.Paste")
			(net "GND")
		)
		(pad "21" smd rect
			(at 2.02489 -5.24992 180)
			(size 1.54991 0.24994)
			(layers "F.Cu" "F.Mask" "F.Paste")
		)
		(pad "22" smd rect
			(at -2.02489 -5.24992 180)
			(size 1.54991 0.24994)
			(layers "F.Cu" "F.Mask" "F.Paste")
			(net "GPS1_RST")
		)
		(pad "23" smd rect
			(at 2.02489 -5.75005 180)
			(size 1.54991 0.24994)
			(layers "F.Cu" "F.Mask" "F.Paste")
		)
		(pad "24" smd rect
			(at -2.02489 -5.75005 180)
			(size 1.54991 0.24994)
			(layers "F.Cu" "F.Mask" "F.Paste")
		)
		(pad "25" smd rect
			(at 2.02489 -6.24992 180)
			(size 1.54991 0.24994)
			(layers "F.Cu" "F.Mask" "F.Paste")
		)
		(pad "26" smd rect
			(at -2.02489 -6.24992 180)
			(size 1.54991 0.24994)
			(layers "F.Cu" "F.Mask" "F.Paste")
		)
		(pad "27" smd rect
			(at 2.02489 -6.75005 180)
			(size 1.54991 0.24994)
			(layers "F.Cu" "F.Mask" "F.Paste")
		)
		(pad "28" smd rect
			(at -2.02489 -6.75005 180)
			(size 1.54991 0.24994)
			(layers "F.Cu" "F.Mask" "F.Paste")
		)
		(pad "29" smd rect
			(at 2.02489 -7.24992 180)
			(size 1.54991 0.24994)
			(layers "F.Cu" "F.Mask" "F.Paste")
			(net "GND")
		)
		(pad "30" smd rect
			(at -2.02489 -7.24992 180)
			(size 1.54991 0.24994)
			(layers "F.Cu" "F.Mask" "F.Paste")
			(net "GND")
		)
		(pad "31" smd rect
			(at 2.02489 -7.75005 180)
			(size 1.54991 0.24994)
			(layers "F.Cu" "F.Mask" "F.Paste")
		)
		(pad "32" smd rect
			(at -2.02489 -7.75005 180)
			(size 1.54991 0.24994)
			(layers "F.Cu" "F.Mask" "F.Paste")
			(net "GPS1_TP1")
		)
		(pad "33" smd rect
			(at 2.02489 -8.24992 180)
			(size 1.54991 0.24994)
			(layers "F.Cu" "F.Mask" "F.Paste")
		)
		(pad "34" smd rect
			(at -2.02489 -8.24992 180)
			(size 1.54991 0.24994)
			(layers "F.Cu" "F.Mask" "F.Paste")
			(net "GPS1_TP2")
		)
		(pad "35" smd rect
			(at 2.02489 -8.75004 180)
			(size 1.54991 0.24994)
			(layers "F.Cu" "F.Mask" "F.Paste")
		)
		(pad "36" smd rect
			(at -2.02489 -8.75004 180)
			(size 1.54991 0.24994)
			(layers "F.Cu" "F.Mask" "F.Paste")
		)
		(pad "37" smd rect
			(at 2.02489 -9.24992 180)
			(size 1.54991 0.24994)
			(layers "F.Cu" "F.Mask" "F.Paste")
		)
		(pad "38" smd rect
			(at -2.02489 -9.24992 180)
			(size 1.54991 0.24994)
			(layers "F.Cu" "F.Mask" "F.Paste")
		)
		(pad "39" smd rect
			(at 2.02489 -9.75004 180)
			(size 1.54991 0.24994)
			(layers "F.Cu" "F.Mask" "F.Paste")
			(net "GND")
		)
		(pad "40" smd rect
			(at -2.02489 -9.75004 180)
			(size 1.54991 0.24994)
			(layers "F.Cu" "F.Mask" "F.Paste")
			(net "GND")
		)
		(pad "41" smd rect
			(at 2.02489 -10.24991 180)
			(size 1.54991 0.24994)
			(layers "F.Cu" "F.Mask" "F.Paste")
		)
		(pad "42" smd rect
			(at -2.02489 -10.24991 180)
			(size 1.54991 0.24994)
			(layers "F.Cu" "F.Mask" "F.Paste")
		)
		(pad "43" smd rect
			(at 2.02489 -10.75004 180)
			(size 1.54991 0.24994)
			(layers "F.Cu" "F.Mask" "F.Paste")
		)
		(pad "44" smd rect
			(at -2.02489 -10.75004 180)
			(size 1.54991 0.24994)
			(layers "F.Cu" "F.Mask" "F.Paste")
			(net "EXT_EEPROM_WP")
		)
		(pad "45" smd rect
			(at 2.02489 -11.24991 180)
			(size 1.54991 0.24994)
			(layers "F.Cu" "F.Mask" "F.Paste")
		)
		(pad "46" smd rect
			(at -2.02489 -11.24991 180)
			(size 1.54991 0.24994)
			(layers "F.Cu" "F.Mask" "F.Paste")
		)
		(pad "47" smd rect
			(at 2.02489 -11.75004 180)
			(size 1.54991 0.24994)
			(layers "F.Cu" "F.Mask" "F.Paste")
		)
		(pad "48" smd rect
			(at -2.02489 -11.75004 180)
			(size 1.54991 0.24994)
			(layers "F.Cu" "F.Mask" "F.Paste")
		)
		(pad "49" smd rect
			(at 2.02489 -12.24991 180)
			(size 1.54991 0.24994)
			(layers "F.Cu" "F.Mask" "F.Paste")
			(net "GND")
		)
		(pad "50" smd rect
			(at -2.02489 -12.24991 180)
			(size 1.54991 0.24994)
			(layers "F.Cu" "F.Mask" "F.Paste")
			(net "GND")
		)
		(pad "51" smd rect
			(at 2.02489 -12.75004 180)
			(size 1.54991 0.24994)
			(layers "F.Cu" "F.Mask" "F.Paste")
		)
		(pad "52" smd rect
			(at -2.02489 -12.75004 180)
			(size 1.54991 0.24994)
			(layers "F.Cu" "F.Mask" "F.Paste")
		)
		(pad "53" smd rect
			(at 2.02489 -13.24991 180)
			(size 1.54991 0.24994)
			(layers "F.Cu" "F.Mask" "F.Paste")
		)
		(pad "54" smd rect
			(at -2.02489 -13.24991 180)
			(size 1.54991 0.24994)
			(layers "F.Cu" "F.Mask" "F.Paste")
		)
		(pad "55" smd rect
			(at 2.02489 -13.75003 180)
			(size 1.54991 0.24994)
			(layers "F.Cu" "F.Mask" "F.Paste")
		)
		(pad "56" smd rect
			(at -2.02489 -13.75003 180)
			(size 1.54991 0.24994)
			(layers "F.Cu" "F.Mask" "F.Paste")
		)
		(pad "57" smd rect
			(at 2.02489 -14.24991 180)
			(size 1.54991 0.24994)
			(layers "F.Cu" "F.Mask" "F.Paste")
		)
		(pad "58" smd rect
			(at -2.02489 -14.24991 180)
			(size 1.54991 0.24994)
			(layers "F.Cu" "F.Mask" "F.Paste")
		)
		(pad "59" smd rect
			(at 2.02489 -14.75003 180)
			(size 1.54991 0.24994)
			(layers "F.Cu" "F.Mask" "F.Paste")
			(net "GND")
		)
		(pad "60" smd rect
			(at -2.02489 -14.75003 180)
			(size 1.54991 0.24994)
			(layers "F.Cu" "F.Mask" "F.Paste")
			(net "GND")
		)
		(pad "61" smd rect
			(at 2.02489 -15.2499 180)
			(size 1.54991 0.24994)
			(layers "F.Cu" "F.Mask" "F.Paste")
		)
		(pad "62" smd rect
			(at -2.02489 -15.2499 180)
			(size 1.54991 0.24994)
			(layers "F.Cu" "F.Mask" "F.Paste")
		)
		(pad "63" smd rect
			(at 2.02489 -15.75003 180)
			(size 1.54991 0.24994)
			(layers "F.Cu" "F.Mask" "F.Paste")
		)
		(pad "64" smd rect
			(at -2.02489 -15.75003 180)
			(size 1.54991 0.24994)
			(layers "F.Cu" "F.Mask" "F.Paste")
		)
		(pad "65" smd rect
			(at 2.02489 -16.2499 180)
			(size 1.54991 0.24994)
			(layers "F.Cu" "F.Mask" "F.Paste")
		)
		(pad "66" smd rect
			(at -2.02489 -16.2499 180)
			(size 1.54991 0.24994)
			(layers "F.Cu" "F.Mask" "F.Paste")
		)
		(pad "67" smd rect
			(at 2.02489 -16.75003 180)
			(size 1.54991 0.24994)
			(layers "F.Cu" "F.Mask" "F.Paste")
			(net "KEY2")
		)
		(pad "68" smd rect
			(at -2.02489 -16.75003 180)
			(size 1.54991 0.24994)
			(layers "F.Cu" "F.Mask" "F.Paste")
		)
		(pad "69" smd rect
			(at 2.02489 -17.2499 180)
			(size 1.54991 0.24994)
			(layers "F.Cu" "F.Mask" "F.Paste")
			(net "GND")
		)
		(pad "70" smd rect
			(at -2.02489 -17.2499 180)
			(size 1.54991 0.24994)
			(layers "F.Cu" "F.Mask" "F.Paste")
			(net "GND")
		)
		(pad "71" smd rect
			(at 2.02489 -17.75003 180)
			(size 1.54991 0.24994)
			(layers "F.Cu" "F.Mask" "F.Paste")
			(net "LED4")
		)
		(pad "72" smd rect
			(at -2.02489 -17.75003 180)
			(size 1.54991 0.24994)
			(layers "F.Cu" "F.Mask" "F.Paste")
		)
		(pad "73" smd rect
			(at 2.02489 -18.2499 180)
			(size 1.54991 0.24994)
			(layers "F.Cu" "F.Mask" "F.Paste")
			(net "LED3")
		)
		(pad "74" smd rect
			(at -2.02489 -18.2499 180)
			(size 1.54991 0.24994)
			(layers "F.Cu" "F.Mask" "F.Paste")
		)
		(pad "75" smd rect
			(at 2.02489 -18.75002 180)
			(size 1.54991 0.24994)
			(layers "F.Cu" "F.Mask" "F.Paste")
			(net "LED2")
		)
		(pad "76" smd rect
			(at -2.02489 -18.75002 180)
			(size 1.54991 0.24994)
			(layers "F.Cu" "F.Mask" "F.Paste")
		)
		(pad "77" smd rect
			(at 2.02489 -19.2499 180)
			(size 1.54991 0.24994)
			(layers "F.Cu" "F.Mask" "F.Paste")
			(net "LED1")
		)
		(pad "78" smd rect
			(at -2.02489 -19.2499 180)
			(size 1.54991 0.24994)
			(layers "F.Cu" "F.Mask" "F.Paste")
		)
		(pad "79" smd rect
			(at 2.02489 -19.75002 180)
			(size 1.54991 0.24994)
			(layers "F.Cu" "F.Mask" "F.Paste")
		)
		(pad "80" smd rect
			(at -2.02489 -19.75002 180)
			(size 1.54991 0.24994)
			(layers "F.Cu" "F.Mask" "F.Paste")
		)
		(pad "81" smd rect
			(at 0.01135 1.17626 180)
			(size 1.70002 1.35001)
			(layers "F.Cu" "F.Mask" "F.Paste")
		)
		(pad "82" thru_hole circle
			(at 0 0 180)
			(size 0.55016 0.55016)
			(drill 0.55016)
			(layers "*.Cu" "*.Mask")
			(remove_unused_layers no)
			(thermal_bridge_angle 90)
		)
		(pad "83" thru_hole circle
			(at 0 -19.99996 180)
			(size 0.55016 0.55016)
			(drill 0.55016)
			(layers "*.Cu" "*.Mask")
			(remove_unused_layers no)
			(thermal_bridge_angle 90)
		)
		(pad "84" smd rect
			(at 0.01135 -21.17374 180)
			(size 1.70002 1.35001)
			(layers "F.Cu" "F.Mask" "F.Paste")
		)
	)
)
